# BASEBOARD_FAB2 (Tioga Pass) — schematic netlist excerpt (pin names and nets, part order shuffled) for the footprints in the layout excerpt that follows; sources: Cadence DE-HDL packaged netlist, KiCad conversion of Wiwynn_Tioga_Pass_MB.brd

R4R1  RES  1.00K 1% CHIP  pkg 0402  page 157 : A = H_CPU0_FAST_WAKE_N ; B = H_CPU0_FAST_WAKE_B_N
CR6W2  DIODE  BAT54WS IC  pkg SMLF  page 247 : C = FM_CPU_MSMI_LVT3_N ; A = FM_CPU_CATERR_MSMI_LVT3_N

(kicad_pcb
	(version 20260206)
	(generator "pcbnew")
	(generator_version "10.0")
	(general
		(thickness 1.6)
		(legacy_teardrops no)
	)
	(paper "A4")
	(title_block
		(title "Wiwynn_Tioga_Pass_MB.brd")
		(comment 1 "Tioga Pass / footprints 2750-2751 of 4770")
	)
	(layers
		(0 "F.Cu" signal "TOP")
		(4 "In1.Cu" signal "L2GND")
		(6 "In2.Cu" signal "L3")
		(8 "In3.Cu" signal "L4GND")
		(10 "In4.Cu" signal "L5")
		(12 "In5.Cu" signal "L6GND")
		(14 "In6.Cu" signal "L7VCC")
		(16 "In7.Cu" signal "L8VCC")
		(18 "In8.Cu" signal "L9GND")
		(20 "In9.Cu" signal "L10")
		(22 "In10.Cu" signal "L11GND")
		(24 "In11.Cu" signal "L12")
		(26 "In12.Cu" signal "L13GND")
		(2 "B.Cu" signal "BOTTOM")
		(9 "F.Adhes" user "F.Adhesive")
		(11 "B.Adhes" user "B.Adhesive")
		(13 "F.Paste" user "Package Geometry/Pastemask Top")
		(15 "B.Paste" user "Package Geometry/Pastemask Bottom")
		(5 "F.SilkS" user "Ref Des/Silkscreen Top")
		(7 "B.SilkS" user "Ref Des/Silkscreen Bottom")
		(1 "F.Mask" user "Board Geometry/Soldermask Top")
		(3 "B.Mask" user "Board Geometry/Soldermask Bottom")
		(17 "Dwgs.User" user "User.Drawings")
		(19 "Cmts.User" user "User.Comments")
		(21 "Eco1.User" user "User.Eco1")
		(23 "Eco2.User" user "User.Eco2")
		(25 "Edge.Cuts" user "Board Geometry/Outline")
		(27 "Margin" user)
		(31 "F.CrtYd" user "Package Geometry/Place Bound Top")
		(29 "B.CrtYd" user "Package Geometry/Place Bound Bottom")
		(35 "F.Fab" user "Ref Des/Assembly Top")
		(33 "B.Fab" user "Ref Des/Assembly Bottom")
	)
	(footprint ""
		(layer "B.Cu")
		(at 469.138 -131.2164 180)
		(property "Reference" "CR6W2"
			(at -1.06934 -0.39116 270)
			(unlocked yes)
			(layer "B.SilkS")
			(effects
				(font
					(size 0.4064 0.254)
					(thickness 0.1524)
				)
				(justify left mirror)
			)
		)
		(property "Value" ""
			(at 0 0 0)
			(layer "B.Fab")
			(effects
				(font
					(size 1.27 1.27)
				)
				(justify mirror)
			)
		)
		(duplicate_pad_numbers_are_jumpers no)
		(fp_line
			(start 1.234186 1.636522)
			(end 0.753364 0.803656)
			(stroke
				(width 0.1524)
				(type default)
			)
			(layer "B.SilkS")
		)
		(fp_line
			(start 0.753364 2.548128)
			(end 0.753364 1.636522)
			(stroke
				(width 0.1524)
				(type default)
			)
			(layer "B.SilkS")
		)
		(fp_line
			(start 0.753364 1.636522)
			(end 1.234186 1.636522)
			(stroke
				(width 0.1524)
				(type default)
			)
			(layer "B.SilkS")
		)
		(fp_line
			(start 0.753364 0.803656)
			(end 0.272542 1.636522)
			(stroke
				(width 0.1524)
				(type default)
			)
			(layer "B.SilkS")
		)
		(fp_line
			(start 0.753364 -0.319786)
			(end 0.753364 0.803656)
			(stroke
				(width 0.1524)
				(type default)
			)
			(layer "B.SilkS")
		)
		(fp_line
			(start 0.272542 1.636522)
			(end 0.753364 1.636522)
			(stroke
				(width 0.1524)
				(type default)
			)
			(layer "B.SilkS")
		)
		(fp_line
			(start 0.272542 0.803656)
			(end 1.234186 0.803656)
			(stroke
				(width 0.1524)
				(type default)
			)
			(layer "B.SilkS")
		)
		(fp_poly
			(pts
				(xy 0.67437 0.24384) (xy 0.67437 2.04216) (xy -0.67437 2.04216) (xy -0.67437 0.24384)
			)
			(stroke
				(width 0)
				(type default)
			)
			(fill no)
			(layer "B.CrtYd")
		)
		(fp_line
			(start 1.229106 1.63195)
			(end 0.748284 0.799084)
			(stroke
				(width 0.1)
				(type default)
			)
			(layer "B.Fab")
		)
		(fp_line
			(start 0.752348 1.628902)
			(end 0.752348 2.540508)
			(stroke
				(width 0.1)
				(type default)
			)
			(layer "B.Fab")
		)
		(fp_line
			(start 0.748284 0.799084)
			(end 0.748284 -0.324358)
			(stroke
				(width 0.1)
				(type default)
			)
			(layer "B.Fab")
		)
		(fp_line
			(start 0.748284 0.799084)
			(end 0.267462 1.63195)
			(stroke
				(width 0.1)
				(type default)
			)
			(layer "B.Fab")
		)
		(fp_line
			(start 0.67437 2.04216)
			(end -0.67437 2.04216)
			(stroke
				(width 0.1)
				(type default)
			)
			(layer "B.Fab")
		)
		(fp_line
			(start 0.67437 0.24384)
			(end 0.67437 2.04216)
			(stroke
				(width 0.1)
				(type default)
			)
			(layer "B.Fab")
		)
		(fp_line
			(start 0.267462 1.63195)
			(end 1.229106 1.63195)
			(stroke
				(width 0.1)
				(type default)
			)
			(layer "B.Fab")
		)
		(fp_line
			(start 0.267462 0.799084)
			(end 1.229106 0.799084)
			(stroke
				(width 0.1)
				(type default)
			)
			(layer "B.Fab")
		)
		(fp_line
			(start -0.67437 2.04216)
			(end -0.67437 0.24384)
			(stroke
				(width 0.1)
				(type default)
			)
			(layer "B.Fab")
		)
		(fp_line
			(start -0.67437 0.24384)
			(end 0.67437 0.24384)
			(stroke
				(width 0.1)
				(type default)
			)
			(layer "B.Fab")
		)
		(pad "1" smd rect
			(at 0 0)
			(size 0.4064 1.016)
			(layers "B.Cu" "B.Mask" "B.Paste")
			(net "FM_CPU_MSMI_LVT3_N")
		)
		(pad "2" smd rect
			(at 0 2.286)
			(size 0.4064 1.016)
			(layers "B.Cu" "B.Mask" "B.Paste")
			(net "FM_CPU_CATERR_MSMI_LVT3_N")
		)
	)
	(footprint ""
		(layer "B.Cu")
		(at 327.025 -60.325 90)
		(property "Reference" "R4R1"
			(at 0 0 90)
			(layer "B.SilkS")
			(hide yes)
			(effects
				(font
					(size 1.27 1.27)
				)
				(justify mirror)
			)
		)
		(property "Value" ""
			(at 0 0 90)
			(layer "B.Fab")
			(effects
				(font
					(size 1.27 1.27)
				)
				(justify mirror)
			)
		)
		(duplicate_pad_numbers_are_jumpers no)
		(fp_poly
			(pts
				(xy 0.2794 -0.1016) (xy -0.2794 -0.1016) (xy -0.2794 0.9906) (xy 0.2794 0.9906)
			)
			(stroke
				(width 0)
				(type default)
			)
			(fill no)
			(layer "B.CrtYd")
		)
		(fp_line
			(start 0.2794 -0.1016)
			(end 0.2794 0.9906)
			(stroke
				(width 0.1)
				(type default)
			)
			(layer "B.Fab")
		)
		(fp_line
			(start -0.2794 -0.1016)
			(end 0.2794 -0.1016)
			(stroke
				(width 0.1)
				(type default)
			)
			(layer "B.Fab")
		)
		(fp_line
			(start 0.2794 0.9906)
			(end -0.2794 0.9906)
			(stroke
				(width 0.1)
				(type default)
			)
			(layer "B.Fab")
		)
		(fp_line
			(start -0.2794 0.9906)
			(end -0.2794 -0.1016)
			(stroke
				(width 0.1)
				(type default)
			)
			(layer "B.Fab")
		)
		(pad "1" smd rect
			(at 0 0 270)
			(size 0.508 0.508)
			(layers "B.Cu" "B.Mask" "B.Paste")
			(net "H_CPU0_FAST_WAKE_N")
		)
		(pad "2" smd rect
			(at 0 0.889 270)
			(size 0.508 0.508)
			(layers "B.Cu" "B.Mask" "B.Paste")
			(net "H_CPU0_FAST_WAKE_B_N")
		)
		(zone
			(layer "B.Cu")
			(hatch none 0.5)
			(connect_pads
				(clearance 0)
			)
			(min_thickness 0.25)
			(keepout
				(tracks allowed)
				(vias not_allowed)
				(pads allowed)
				(copperpour not_allowed)
				(footprints allowed)
			)
			(placement
				(enabled no)
				(sheetname "")
			)
			(fill
				(thermal_gap 0.5)
				(thermal_bridge_width 0.5)
				(island_removal_mode 0)
			)
			(polygon
				(pts
					(xy 327.279 -60.579) (xy 327.279 -60.071) (xy 327.66 -60.071) (xy 327.66 -60.579)
				)
			)
		)
		(zone
			(layer "B.Cu")
			(hatch none 0.5)
			(connect_pads
				(clearance 0)
			)
			(min_thickness 0.25)
			(keepout
				(tracks not_allowed)
				(vias allowed)
				(pads allowed)
				(copperpour not_allowed)
				(footprints allowed)
			)
			(placement
				(enabled no)
				(sheetname "")
			)
			(fill
				(thermal_gap 0.5)
				(thermal_bridge_width 0.5)
				(island_removal_mode 0)
			)
			(polygon
				(pts
					(xy 327.66 -60.579) (xy 327.66 -60.071) (xy 327.279 -60.071) (xy 327.279 -60.579)
				)
			)
		)
	)
)
